FILE_TYPE = MACRO_DRAWING;
SET COLOR_WIRE YELLOW;
SET COLOR_PROP ORANGE;
SET COLOR_DOT WHITE;
SET COLOR_ARC YELLOW;
SET COLOR_BODY GREEN;
SET COLOR_NOTE PURPLE;
SET PROP_DISPLAY VALUE;
SET PAGE_NUMBER P132;
FORCEADD OFFPAGE..1
(-7300 3275);
FORCEPROP 2 LAST $XR0 139 
J 0
(-7552 3275);
DISPLAY 0.638298 (-7552 3275);
PAINT MONO (-7552 3275);
FORCEPROP 2 LAST ROOM SB_PU_PD
J 0
(-6975 3325);
DISPLAY 1.361702 (-6975 3325);
PAINT RED (-6975 3325);
DISPLAY INVISIBLE (-6975 3325);
FORCEPROP 2 LAST BOM_COST SB
J 0
(-6975 3325);
DISPLAY 1.361702 (-6975 3325);
PAINT WHITE (-6975 3325);
DISPLAY INVISIBLE (-6975 3325);
FORCEPROP 2 LAST CDS_LIB mstr_standard
J 0
(-7300 3275);
DISPLAY 0.808511 (-7300 3275);
DISPLAY INVISIBLE (-7300 3275);
FORCEPROP 1 LAST OFFPAGE TRUE
J 0
(-6975 3150);
DISPLAY 0.872340 (-6975 3150);
PAINT GREEN (-6975 3150);
DISPLAY INVISIBLE (-6975 3150);
FORCEPROP 1 LAST COMMENT_BODY TRUE
J 0
(-7175 3175);
DISPLAY 0.872340 (-7175 3175);
PAINT GREEN (-7175 3175);
DISPLAY INVISIBLE (-7175 3175);
FORCEPROP 2 LAST PATH I1
J 0
(-7550 3325);
DISPLAY 0.680851 (-7550 3325);
DISPLAY INVISIBLE (-7550 3325);
FORCEADD Q_RES..1
R 2
(-3075 4125);
FORCEPROP 1 LAST LOCATION R1009
J 2
(-3125 4125);
DISPLAY 0.489362 (-3125 4125);
PAINT SKYBLUE (-3125 4125);
FORCEPROP 0 LAST $SEC 1
J 0
(-2825 4175);
DISPLAY 0.680851 (-2825 4175);
PAINT MONO (-2825 4175);
DISPLAY INVISIBLE (-2825 4175);
FORCEPROP 2 LAST CDS_SEC 1
J 0
(-3125 4350);
DISPLAY 1.021277 (-3125 4350);
DISPLAY INVISIBLE (-3125 4350);
FORCEPROP 1 LASTPIN (-2975 4125) $PN 1
J 2
(-2987 4137);
DISPLAY 0.489362 (-2987 4137);
PAINT MONO (-2987 4137);
FORCEPROP 1 LASTPIN (-3175 4125) $PN 2
J 2
(-3137 4137);
DISPLAY 0.489362 (-3137 4137);
PAINT MONO (-3137 4137);
FORCEPROP 1 LAST PACK_TYPE 0402LF
J 2
(-2825 4125);
DISPLAY 0.489362 (-2825 4125);
PAINT SKYBLUE (-2825 4125);
FORCEPROP 1 LAST VALUE 10K
J 0
(-3000 4100);
DISPLAY 0.489362 (-3000 4100);
PAINT SKYBLUE (-3000 4100);
FORCEPROP 1 LAST MATERIAL CHIP
J 2
(-3125 4100);
DISPLAY 0.489362 (-3125 4100);
PAINT SKYBLUE (-3125 4100);
FORCEPROP 1 LAST TOLERANCE 1%
J 2
(-3075 4025);
DISPLAY 0.638298 (-3075 4025);
PAINT SKYBLUE (-3075 4025);
DISPLAY INVISIBLE (-3075 4025);
FORCEPROP 1 LAST WATTAGE 1/16W
J 0
(-3050 3975);
DISPLAY 0.638298 (-3050 3975);
PAINT SKYBLUE (-3050 3975);
DISPLAY INVISIBLE (-3050 3975);
FORCEPROP 2 LAST CDS_LIB pure_quanta
J 2
(-3075 4125);
PAINT MONO (-3075 4125);
DISPLAY INVISIBLE (-3075 4125);
FORCEPROP 1 LAST PATH I10
J 2
(-3025 4275);
DISPLAY 0.978723 (-3025 4275);
PAINT WHITE (-3025 4275);
DISPLAY INVISIBLE (-3025 4275);
FORCEPROP 1 LAST PART_NUMBER CS31002FB08
J 2
(-3025 4225);
DISPLAY 0.638298 (-3025 4225);
PAINT SKYBLUE (-3025 4225);
DISPLAY INVISIBLE (-3025 4225);
FORCEADD UNIVERSAL_GND..1
R 7
(-2950 4500);
FORCEPROP 3 LASTPIN (-2900 4500) SIG_NAME GND\g
J 0
(-2890 4510);
DISPLAY 0.659574 (-2890 4510);
PAINT MONO (-2890 4510);
DISPLAY INVISIBLE (-2890 4510);
FORCEPROP 2 LAST CDS_LIB pure_quanta_power
R 1
J 0
(-2950 4500);
DISPLAY INVISIBLE (-2950 4500);
FORCEPROP 1 LAST HDL_POWER GND
R 1
J 1
(-3025 4525);
DISPLAY 0.872340 (-3025 4525);
PAINT GREEN (-3025 4525);
DISPLAY INVISIBLE (-3025 4525);
FORCEPROP 1 LAST PATH I11
R 1
J 0
(-2950 4575);
DISPLAY 0.872340 (-2950 4575);
PAINT AQUA (-2950 4575);
DISPLAY INVISIBLE (-2950 4575);
FORCEADD MOSFET_DUAL_6P..1
(-2475 4450);
FORCEPROP 1 LAST LOCATION Q4
J 0
(-2622 4659);
DISPLAY 0.489362 (-2622 4659);
PAINT SKYBLUE (-2622 4659);
FORCEPROP 2 LAST $SEC 1
J 0
(-2600 4800);
DISPLAY 0.680851 (-2600 4800);
PAINT MONO (-2600 4800);
DISPLAY INVISIBLE (-2600 4800);
FORCEPROP 2 LAST CDS_SEC 1
J 0
(-2600 4800);
DISPLAY 0.680851 (-2600 4800);
DISPLAY INVISIBLE (-2600 4800);
FORCEPROP 2 LASTPIN (-2775 4400) $PN 6
J 2
(-2785 4410);
DISPLAY 0.489362 (-2785 4410);
PAINT MONO (-2785 4410);
FORCEPROP 2 LASTPIN (-2175 4400) $PN 3
J 0
(-2165 4410);
DISPLAY 0.489362 (-2165 4410);
PAINT MONO (-2165 4410);
FORCEPROP 2 LASTPIN (-2775 4450) $PN 2
J 2
(-2785 4460);
DISPLAY 0.489362 (-2785 4460);
PAINT MONO (-2785 4460);
FORCEPROP 2 LASTPIN (-2175 4450) $PN 5
J 0
(-2165 4460);
DISPLAY 0.489362 (-2165 4460);
PAINT MONO (-2165 4460);
FORCEPROP 2 LASTPIN (-2775 4500) $PN 1
J 2
(-2785 4510);
DISPLAY 0.489362 (-2785 4510);
PAINT MONO (-2785 4510);
FORCEPROP 2 LASTPIN (-2175 4500) $PN 4
J 0
(-2165 4510);
DISPLAY 0.489362 (-2165 4510);
PAINT MONO (-2165 4510);
FORCEPROP 2 LAST VALUE 2N7002KDW
J 0
(-2600 4700);
DISPLAY 0.489362 (-2600 4700);
PAINT SKYBLUE (-2600 4700);
FORCEPROP 1 LAST MATERIAL IC
J 0
(-2622 4573);
DISPLAY 0.489362 (-2622 4573);
PAINT SKYBLUE (-2622 4573);
FORCEPROP 2 LAST PART_TYPE SMLF
J 0
(-2600 4750);
DISPLAY 0.680851 (-2600 4750);
FORCEPROP 2 LAST CDS_LIB pure_quanta
J 0
(-2475 4450);
DISPLAY INVISIBLE (-2475 4450);
FORCEPROP 1 LAST NEEDS_NO_SIZE TRUE
J 0
(-2475 4449);
DISPLAY 0.468085 (-2475 4449);
PAINT GREEN (-2475 4449);
DISPLAY INVISIBLE (-2475 4449);
FORCEPROP 1 LAST CDS_LMAN_SYM_OUTLINE -150,100,150,-100
J 0
(-2475 4450);
DISPLAY 0.468085 (-2475 4450);
PAINT GREEN (-2475 4450);
DISPLAY INVISIBLE (-2475 4450);
FORCEPROP 1 LAST PATH I12
J 0
(-2475 4450);
DISPLAY 0.723404 (-2475 4450);
PAINT GREEN (-2475 4450);
DISPLAY INVISIBLE (-2475 4450);
FORCEPROP 1 LAST PART_NUMBER BAM70020047
J 0
(-2622 4617);
DISPLAY 0.489362 (-2622 4617);
PAINT SKYBLUE (-2622 4617);
DISPLAY INVISIBLE (-2622 4617);
FORCEADD UNIVERSAL_POWER..1
(-2725 4275);
FORCEPROP 3 LASTPIN (-2725 4225) SIG_NAME P3V3_AUX\g
J 0
(-2715 4235);
DISPLAY 0.659574 (-2715 4235);
PAINT MONO (-2715 4235);
DISPLAY INVISIBLE (-2715 4235);
FORCEPROP 1 LAST HDL_POWER P3V3_AUX
J 1
(-2725 4325);
DISPLAY 0.489362 (-2725 4325);
PAINT GREEN (-2725 4325);
FORCEPROP 2 LAST CDS_LIB pure_quanta_power
J 0
(-2725 4275);
PAINT MONO (-2725 4275);
DISPLAY INVISIBLE (-2725 4275);
FORCEPROP 1 LAST PATH I13
J 0
(-2675 4300);
DISPLAY 0.872340 (-2675 4300);
PAINT AQUA (-2675 4300);
DISPLAY INVISIBLE (-2675 4300);
FORCEADD UNIVERSAL_GND..1
R 1
(-2075 4500);
FORCEPROP 3 LASTPIN (-2125 4500) SIG_NAME GND\g
J 0
(-2115 4510);
DISPLAY 0.659574 (-2115 4510);
PAINT MONO (-2115 4510);
DISPLAY INVISIBLE (-2115 4510);
FORCEPROP 2 LAST CDS_LIB pure_quanta_power
J 2
(-2075 4500);
DISPLAY INVISIBLE (-2075 4500);
FORCEPROP 1 LAST HDL_POWER GND
R 1
J 1
(-2000 4525);
DISPLAY 0.872340 (-2000 4525);
PAINT GREEN (-2000 4525);
DISPLAY INVISIBLE (-2000 4525);
FORCEPROP 1 LAST PATH I14
R 1
J 0
(-2075 4575);
DISPLAY 0.872340 (-2075 4575);
PAINT AQUA (-2075 4575);
DISPLAY INVISIBLE (-2075 4575);
FORCEADD OFFPAGE..4
(-1650 4450);
FORCEPROP 2 LAST $XR0 155 
J 0
(-1464 4450);
DISPLAY 0.638298 (-1464 4450);
PAINT MONO (-1464 4450);
FORCEPROP 2 LAST CDS_LIB standard
J 0
(-1650 4450);
DISPLAY INVISIBLE (-1650 4450);
FORCEPROP 1 LAST OFFPAGE TRUE
J 0
(-1325 4325);
DISPLAY 0.872340 (-1325 4325);
PAINT GREEN (-1325 4325);
DISPLAY INVISIBLE (-1325 4325);
FORCEPROP 1 LAST COMMENT_BODY TRUE
J 0
(-1675 4350);
DISPLAY 0.872340 (-1675 4350);
PAINT GREEN (-1675 4350);
DISPLAY INVISIBLE (-1675 4350);
FORCEPROP 2 LAST PATH I15
J 0
(-1450 4500);
DISPLAY 0.680851 (-1450 4500);
DISPLAY INVISIBLE (-1450 4500);
FORCEADD Q_RES..1
(-1525 4400);
FORCEPROP 1 LAST LOCATION R1311
J 0
(-1675 4400);
DISPLAY 0.489362 (-1675 4400);
PAINT SKYBLUE (-1675 4400);
FORCEPROP 0 LAST $SEC 1
J 0
(-1675 4425);
DISPLAY 0.680851 (-1675 4425);
PAINT MONO (-1675 4425);
DISPLAY INVISIBLE (-1675 4425);
FORCEPROP 0 LAST CDS_SEC 1
J 0
(-1675 4425);
DISPLAY 0.680851 (-1675 4425);
DISPLAY INVISIBLE (-1675 4425);
FORCEPROP 1 LASTPIN (-1625 4400) $PN 1
J 0
(-1613 4412);
DISPLAY 0.489362 (-1613 4412);
PAINT MONO (-1613 4412);
FORCEPROP 1 LASTPIN (-1425 4400) $PN 2
J 0
(-1463 4412);
DISPLAY 0.489362 (-1463 4412);
PAINT MONO (-1463 4412);
FORCEPROP 1 LAST VALUE 33
J 2
(-1625 4375);
DISPLAY 0.489362 (-1625 4375);
PAINT SKYBLUE (-1625 4375);
FORCEPROP 1 LAST TOLERANCE 5%
J 0
(-1450 4375);
DISPLAY 0.489362 (-1450 4375);
PAINT SKYBLUE (-1450 4375);
FORCEPROP 2 LAST CDS_LIB pure_quanta
J 0
(-1525 4400);
DISPLAY INVISIBLE (-1525 4400);
FORCEPROP 1 LAST WATTAGE 1/16W
J 2
(-1350 4525);
DISPLAY 0.617021 (-1350 4525);
PAINT SKYBLUE (-1350 4525);
DISPLAY INVISIBLE (-1350 4525);
FORCEPROP 1 LAST MATERIAL CHIP
J 0
(-1625 4525);
DISPLAY 0.617021 (-1625 4525);
PAINT SKYBLUE (-1625 4525);
DISPLAY INVISIBLE (-1625 4525);
FORCEPROP 1 LAST PACK_TYPE 0402LF
J 0
(-1225 4400);
DISPLAY 0.617021 (-1225 4400);
PAINT SKYBLUE (-1225 4400);
DISPLAY INVISIBLE (-1225 4400);
FORCEPROP 1 LAST PATH I16
J 0
(-1575 4550);
DISPLAY 0.978723 (-1575 4550);
PAINT WHITE (-1575 4550);
DISPLAY INVISIBLE (-1575 4550);
FORCEPROP 1 LAST PART_NUMBER CS03302JB10
J 0
(-1625 4475);
DISPLAY 0.617021 (-1625 4475);
PAINT SKYBLUE (-1625 4475);
DISPLAY INVISIBLE (-1625 4475);
FORCEADD OFFPAGE..2
(-1100 4400);
FORCEPROP 2 LAST $XR1 55 
J 0
(-821 4400);
DISPLAY 0.638298 (-821 4400);
PAINT MONO (-821 4400);
FORCEPROP 2 LAST $XR0 28 
J 0
(-911 4400);
DISPLAY 0.638298 (-911 4400);
PAINT MONO (-911 4400);
FORCEPROP 2 LAST CDS_LIB standard
J 0
(-1100 4400);
DISPLAY INVISIBLE (-1100 4400);
FORCEPROP 1 LAST OFFPAGE TRUE
J 0
(-775 4275);
DISPLAY 0.872340 (-775 4275);
PAINT GREEN (-775 4275);
DISPLAY INVISIBLE (-775 4275);
FORCEPROP 1 LAST COMMENT_BODY TRUE
J 0
(-1145 4305);
DISPLAY 0.872340 (-1145 4305);
PAINT GREEN (-1145 4305);
DISPLAY INVISIBLE (-1145 4305);
FORCEPROP 2 LAST PATH I17
J 0
(-800 4450);
DISPLAY 0.680851 (-800 4450);
DISPLAY INVISIBLE (-800 4450);
FORCEADD Q_RES..2
(-1175 4650);
FORCEPROP 1 LAST LOCATION R437
J 0
(-1125 4700);
DISPLAY 0.489362 (-1125 4700);
PAINT SKYBLUE (-1125 4700);
FORCEPROP 0 LAST $SEC 1
J 0
(-1125 4725);
DISPLAY 0.680851 (-1125 4725);
PAINT MONO (-1125 4725);
DISPLAY INVISIBLE (-1125 4725);
FORCEPROP 0 LAST CDS_SEC 1
J 0
(-1125 4725);
DISPLAY 0.680851 (-1125 4725);
DISPLAY INVISIBLE (-1125 4725);
FORCEPROP 1 LASTPIN (-1175 4750) $PN 1
J 0
(-1170 4712);
DISPLAY 0.489362 (-1170 4712);
PAINT MONO (-1170 4712);
FORCEPROP 1 LASTPIN (-1175 4550) $PN 2
J 0
(-1170 4560);
DISPLAY 0.489362 (-1170 4560);
PAINT MONO (-1170 4560);
FORCEPROP 1 LAST PACK_TYPE 0402LF
J 0
(-1125 4550);
DISPLAY 0.489362 (-1125 4550);
PAINT SKYBLUE (-1125 4550);
FORCEPROP 1 LAST VALUE 2.2K
J 0
(-1125 4650);
DISPLAY 0.489362 (-1125 4650);
PAINT SKYBLUE (-1125 4650);
FORCEPROP 1 LAST TOLERANCE 5%
J 0
(-1130 4675);
DISPLAY 0.510638 (-1130 4675);
PAINT SKYBLUE (-1130 4675);
DISPLAY INVISIBLE (-1130 4675);
FORCEPROP 1 LAST MATERIAL CHIP
J 0
(-1135 4575);
DISPLAY 0.510638 (-1135 4575);
PAINT SKYBLUE (-1135 4575);
DISPLAY INVISIBLE (-1135 4575);
FORCEPROP 1 LAST WATTAGE 1/16W
J 0
(-1135 4625);
DISPLAY 0.510638 (-1135 4625);
PAINT SKYBLUE (-1135 4625);
DISPLAY INVISIBLE (-1135 4625);
FORCEPROP 2 LAST CDS_LIB pure_quanta
J 0
(-1175 4650);
DISPLAY INVISIBLE (-1175 4650);
FORCEPROP 1 LAST PATH I18
J 0
(-1125 4825);
DISPLAY 0.978723 (-1125 4825);
PAINT WHITE (-1125 4825);
DISPLAY INVISIBLE (-1125 4825);
FORCEPROP 1 LAST PART_NUMBER CS22202JB07
J 0
(-1125 4600);
DISPLAY 0.489362 (-1125 4600);
PAINT SKYBLUE (-1125 4600);
DISPLAY INVISIBLE (-1125 4600);
FORCEADD UNIVERSAL_POWER..1
(-1175 4850);
FORCEPROP 3 LASTPIN (-1175 4800) SIG_NAME PVDD18_S5_P0\g
J 0
(-1165 4810);
DISPLAY 0.659574 (-1165 4810);
PAINT MONO (-1165 4810);
DISPLAY INVISIBLE (-1165 4810);
FORCEPROP 1 LAST HDL_POWER PVDD18_S5_P0
J 1
(-1175 4900);
DISPLAY 0.489362 (-1175 4900);
PAINT GREEN (-1175 4900);
FORCEPROP 2 LAST CDS_LIB pure_quanta_power
J 0
(-1175 4850);
DISPLAY INVISIBLE (-1175 4850);
FORCEPROP 1 LAST PATH I19
J 0
(-1125 4875);
DISPLAY 0.872340 (-1125 4875);
PAINT AQUA (-1125 4875);
DISPLAY INVISIBLE (-1125 4875);
FORCEADD OFFPAGE..1
(-7300 2975);
FORCEPROP 2 LAST $XR0 144 
J 0
(-7552 2975);
DISPLAY 0.638298 (-7552 2975);
PAINT MONO (-7552 2975);
FORCEPROP 2 LAST ROOM SB_PU_PD
J 0
(-6975 3025);
DISPLAY 1.361702 (-6975 3025);
PAINT RED (-6975 3025);
DISPLAY INVISIBLE (-6975 3025);
FORCEPROP 2 LAST CDS_LIB mstr_standard
J 0
(-7300 2975);
DISPLAY INVISIBLE (-7300 2975);
FORCEPROP 2 LAST BOM_COST SB
J 0
(-6975 3025);
DISPLAY 1.361702 (-6975 3025);
PAINT WHITE (-6975 3025);
DISPLAY INVISIBLE (-6975 3025);
FORCEPROP 1 LAST OFFPAGE TRUE
J 0
(-6975 2850);
DISPLAY 0.872340 (-6975 2850);
PAINT GREEN (-6975 2850);
DISPLAY INVISIBLE (-6975 2850);
FORCEPROP 1 LAST COMMENT_BODY TRUE
J 0
(-7175 2875);
DISPLAY 0.872340 (-7175 2875);
PAINT GREEN (-7175 2875);
DISPLAY INVISIBLE (-7175 2875);
FORCEPROP 2 LAST PATH I2
J 0
(-7550 3025);
DISPLAY 0.680851 (-7550 3025);
DISPLAY INVISIBLE (-7550 3025);
FORCEADD OFFPAGE..1
(-7300 3450);
FORCEPROP 2 LAST $XR0 133 
J 0
(-7552 3450);
DISPLAY 0.638298 (-7552 3450);
PAINT MONO (-7552 3450);
FORCEPROP 2 LAST CDS_LIB mstr_standard
J 0
(-7300 3450);
DISPLAY 0.808511 (-7300 3450);
DISPLAY INVISIBLE (-7300 3450);
FORCEPROP 2 LAST BOM_COST SB
J 0
(-6975 3500);
DISPLAY 1.361702 (-6975 3500);
PAINT WHITE (-6975 3500);
DISPLAY INVISIBLE (-6975 3500);
FORCEPROP 2 LAST ROOM SB_PU_PD
J 0
(-6975 3500);
DISPLAY 1.361702 (-6975 3500);
PAINT RED (-6975 3500);
DISPLAY INVISIBLE (-6975 3500);
FORCEPROP 1 LAST OFFPAGE TRUE
J 0
(-6975 3325);
DISPLAY 0.872340 (-6975 3325);
PAINT GREEN (-6975 3325);
DISPLAY INVISIBLE (-6975 3325);
FORCEPROP 1 LAST COMMENT_BODY TRUE
J 0
(-7175 3350);
DISPLAY 0.872340 (-7175 3350);
PAINT GREEN (-7175 3350);
DISPLAY INVISIBLE (-7175 3350);
FORCEPROP 2 LAST PATH I3
J 0
(-7550 3500);
DISPLAY 0.680851 (-7550 3500);
DISPLAY INVISIBLE (-7550 3500);
FORCEADD Q_RES..1
(-5925 2975);
FORCEPROP 1 LAST LOCATION R1005
J 0
(-6175 2975);
DISPLAY 0.489362 (-6175 2975);
PAINT SKYBLUE (-6175 2975);
FORCEPROP 0 LAST $SEC 1
J 0
(-5975 3075);
DISPLAY 0.680851 (-5975 3075);
PAINT MONO (-5975 3075);
DISPLAY INVISIBLE (-5975 3075);
FORCEPROP 0 LAST CDS_SEC 1
J 0
(-5975 3075);
DISPLAY 1.021277 (-5975 3075);
DISPLAY INVISIBLE (-5975 3075);
FORCEPROP 1 LASTPIN (-6025 2975) $PN 1
J 0
(-6013 2987);
DISPLAY 0.489362 (-6013 2987);
PAINT MONO (-6013 2987);
FORCEPROP 1 LASTPIN (-5825 2975) $PN 2
J 0
(-5863 2987);
DISPLAY 0.489362 (-5863 2987);
PAINT MONO (-5863 2987);
FORCEPROP 1 LAST VALUE 33
J 2
(-5725 2975);
DISPLAY 0.489362 (-5725 2975);
PAINT SKYBLUE (-5725 2975);
FORCEPROP 1 LAST TOLERANCE 5%
J 0
(-5700 2975);
DISPLAY 0.489362 (-5700 2975);
PAINT SKYBLUE (-5700 2975);
FORCEPROP 2 LAST CDS_LIB pure_quanta
J 0
(-5925 2975);
DISPLAY INVISIBLE (-5925 2975);
FORCEPROP 1 LAST WATTAGE 1/16W
J 2
(-5750 3100);
DISPLAY 0.617021 (-5750 3100);
PAINT SKYBLUE (-5750 3100);
DISPLAY INVISIBLE (-5750 3100);
FORCEPROP 1 LAST MATERIAL CHIP
J 0
(-6025 3100);
DISPLAY 0.617021 (-6025 3100);
PAINT SKYBLUE (-6025 3100);
DISPLAY INVISIBLE (-6025 3100);
FORCEPROP 1 LAST PACK_TYPE 0402LF
J 0
(-5625 2975);
DISPLAY 0.617021 (-5625 2975);
PAINT SKYBLUE (-5625 2975);
DISPLAY INVISIBLE (-5625 2975);
FORCEPROP 1 LAST PATH I4
J 0
(-5975 3125);
DISPLAY 0.978723 (-5975 3125);
PAINT WHITE (-5975 3125);
DISPLAY INVISIBLE (-5975 3125);
FORCEPROP 1 LAST PART_NUMBER CS03302JB10
J 0
(-6025 3050);
DISPLAY 0.617021 (-6025 3050);
PAINT SKYBLUE (-6025 3050);
DISPLAY INVISIBLE (-6025 3050);
FORCEADD Q_RES..1
(-5925 3450);
FORCEPROP 1 LAST LOCATION R116
J 0
(-6150 3450);
DISPLAY 0.489362 (-6150 3450);
PAINT SKYBLUE (-6150 3450);
FORCEPROP 0 LAST $SEC 1
J 0
(-5725 3600);
DISPLAY 0.680851 (-5725 3600);
PAINT MONO (-5725 3600);
DISPLAY INVISIBLE (-5725 3600);
FORCEPROP 0 LAST CDS_SEC 1
J 0
(-5725 3600);
DISPLAY 1.021277 (-5725 3600);
DISPLAY INVISIBLE (-5725 3600);
FORCEPROP 1 LASTPIN (-6025 3450) $PN 1
J 0
(-6013 3462);
DISPLAY 0.489362 (-6013 3462);
PAINT MONO (-6013 3462);
FORCEPROP 1 LASTPIN (-5825 3450) $PN 2
J 0
(-5863 3462);
DISPLAY 0.489362 (-5863 3462);
PAINT MONO (-5863 3462);
FORCEPROP 1 LAST VALUE 33
J 2
(-5750 3450);
DISPLAY 0.489362 (-5750 3450);
PAINT SKYBLUE (-5750 3450);
FORCEPROP 1 LAST PACK_TYPE 0402LF
J 0
(-5800 3350);
DISPLAY 0.489362 (-5800 3350);
PAINT SKYBLUE (-5800 3350);
FORCEPROP 1 LAST WATTAGE 1/16W
J 2
(-6025 3350);
DISPLAY 0.489362 (-6025 3350);
PAINT SKYBLUE (-6025 3350);
FORCEPROP 1 LAST MATERIAL CHIP
J 0
(-5700 3450);
DISPLAY 0.489362 (-5700 3450);
PAINT SKYBLUE (-5700 3450);
FORCEPROP 1 LAST TOLERANCE 5%
J 0
(-6125 3400);
DISPLAY 0.489362 (-6125 3400);
PAINT SKYBLUE (-6125 3400);
FORCEPROP 2 LAST CDS_LIB pure_quanta
J 0
(-5925 3450);
DISPLAY INVISIBLE (-5925 3450);
FORCEPROP 2 LAST BOM_COST PCH
J 0
(-5775 3525);
DISPLAY 1.361702 (-5775 3525);
DISPLAY INVISIBLE (-5775 3525);
FORCEPROP 1 LAST PATH I5
J 0
(-5975 3600);
DISPLAY 0.978723 (-5975 3600);
PAINT WHITE (-5975 3600);
DISPLAY INVISIBLE (-5975 3600);
FORCEPROP 1 LAST PART_NUMBER CS03302JB10
J 0
(-5800 3400);
DISPLAY 0.489362 (-5800 3400);
PAINT SKYBLUE (-5800 3400);
DISPLAY INVISIBLE (-5800 3400);
FORCEADD Q_RES..1
(-5925 3275);
FORCEPROP 1 LAST LOCATION R6063
J 0
(-6150 3275);
DISPLAY 0.489362 (-6150 3275);
PAINT SKYBLUE (-6150 3275);
FORCEPROP 0 LAST $SEC 1
J 0
(-5725 3425);
DISPLAY 0.680851 (-5725 3425);
PAINT MONO (-5725 3425);
DISPLAY INVISIBLE (-5725 3425);
FORCEPROP 0 LAST CDS_SEC 1
J 0
(-5725 3425);
DISPLAY 1.021277 (-5725 3425);
DISPLAY INVISIBLE (-5725 3425);
FORCEPROP 1 LASTPIN (-6025 3275) $PN 1
J 0
(-6013 3287);
DISPLAY 0.489362 (-6013 3287);
PAINT MONO (-6013 3287);
FORCEPROP 1 LASTPIN (-5825 3275) $PN 2
J 0
(-5863 3287);
DISPLAY 0.489362 (-5863 3287);
PAINT MONO (-5863 3287);
FORCEPROP 1 LAST MATERIAL CHIP
J 0
(-5700 3275);
DISPLAY 0.489362 (-5700 3275);
PAINT SKYBLUE (-5700 3275);
FORCEPROP 1 LAST VALUE 33
J 2
(-5750 3275);
DISPLAY 0.489362 (-5750 3275);
PAINT SKYBLUE (-5750 3275);
FORCEPROP 1 LAST PACK_TYPE 0402LF
J 0
(-5800 3175);
DISPLAY 0.489362 (-5800 3175);
PAINT SKYBLUE (-5800 3175);
FORCEPROP 1 LAST WATTAGE 1/16W
J 2
(-6025 3175);
DISPLAY 0.489362 (-6025 3175);
PAINT SKYBLUE (-6025 3175);
FORCEPROP 1 LAST TOLERANCE 5%
J 0
(-6125 3225);
DISPLAY 0.489362 (-6125 3225);
PAINT SKYBLUE (-6125 3225);
FORCEPROP 2 LAST BOM_COST PCH
J 0
(-5775 3350);
DISPLAY 1.361702 (-5775 3350);
DISPLAY INVISIBLE (-5775 3350);
FORCEPROP 2 LAST CDS_LIB pure_quanta
J 0
(-5925 3275);
DISPLAY INVISIBLE (-5925 3275);
FORCEPROP 1 LAST PATH I6
J 0
(-5975 3425);
DISPLAY 0.978723 (-5975 3425);
PAINT WHITE (-5975 3425);
DISPLAY INVISIBLE (-5975 3425);
FORCEPROP 1 LAST PART_NUMBER CS03302JB10
J 0
(-5800 3225);
DISPLAY 0.489362 (-5800 3225);
PAINT SKYBLUE (-5800 3225);
DISPLAY INVISIBLE (-5800 3225);
FORCEADD Q_RES..2
R 2
(-4250 4675);
FORCEPROP 1 LAST LOCATION R994
J 2
(-4300 4875);
DISPLAY 0.489362 (-4300 4875);
PAINT SKYBLUE (-4300 4875);
FORCEPROP 0 LAST $SEC 1
J 0
(-4300 4925);
DISPLAY 0.680851 (-4300 4925);
PAINT MONO (-4300 4925);
DISPLAY INVISIBLE (-4300 4925);
FORCEPROP 0 LAST CDS_SEC 1
J 0
(-4300 4925);
DISPLAY 0.680851 (-4300 4925);
DISPLAY INVISIBLE (-4300 4925);
FORCEPROP 1 LASTPIN (-4250 4775) $PN 1
J 2
(-4255 4737);
DISPLAY 0.489362 (-4255 4737);
PAINT MONO (-4255 4737);
FORCEPROP 1 LASTPIN (-4250 4575) $PN 2
J 2
(-4255 4585);
DISPLAY 0.489362 (-4255 4585);
PAINT MONO (-4255 4585);
FORCEPROP 1 LAST TOLERANCE 1%
J 2
(-4305 4775);
DISPLAY 0.489362 (-4305 4775);
PAINT SKYBLUE (-4305 4775);
FORCEPROP 1 LAST PACK_TYPE 0402LF
J 2
(-4300 4575);
DISPLAY 0.489362 (-4300 4575);
PAINT SKYBLUE (-4300 4575);
FORCEPROP 1 LAST MATERIAL CHIP
J 2
(-4300 4675);
DISPLAY 0.489362 (-4300 4675);
PAINT SKYBLUE (-4300 4675);
FORCEPROP 1 LAST VALUE 10K
J 2
(-4305 4825);
DISPLAY 0.489362 (-4305 4825);
PAINT SKYBLUE (-4305 4825);
FORCEPROP 1 LAST WATTAGE 1/16W
J 2
(-4300 4725);
DISPLAY 0.489362 (-4300 4725);
PAINT SKYBLUE (-4300 4725);
FORCEPROP 2 LAST CDS_LIB pure_quanta
J 0
(-4250 4675);
DISPLAY INVISIBLE (-4250 4675);
FORCEPROP 1 LAST PATH I7
J 2
(-4300 4850);
DISPLAY 0.978723 (-4300 4850);
PAINT WHITE (-4300 4850);
DISPLAY INVISIBLE (-4300 4850);
FORCEPROP 1 LAST PART_NUMBER CS31002FB08
J 2
(-4300 4625);
DISPLAY 0.489362 (-4300 4625);
PAINT SKYBLUE (-4300 4625);
DISPLAY INVISIBLE (-4300 4625);
FORCEADD UNIVERSAL_POWER..1
(-4250 4925);
FORCEPROP 3 LASTPIN (-4250 4875) SIG_NAME P3V3_AUX\g
J 0
(-4240 4885);
DISPLAY 0.659574 (-4240 4885);
PAINT MONO (-4240 4885);
DISPLAY INVISIBLE (-4240 4885);
FORCEPROP 1 LAST HDL_POWER P3V3_AUX
J 1
(-4250 4975);
DISPLAY 0.489362 (-4250 4975);
PAINT GREEN (-4250 4975);
FORCEPROP 2 LAST CDS_LIB pure_quanta_power
J 0
(-4250 4925);
DISPLAY INVISIBLE (-4250 4925);
FORCEPROP 1 LAST PATH I8
J 0
(-4200 4950);
DISPLAY 0.872340 (-4200 4950);
PAINT AQUA (-4200 4950);
DISPLAY INVISIBLE (-4200 4950);
FORCEADD OFFPAGE..5
(-3550 4400);
FORCEPROP 2 LAST $XR0 155 
J 0
(-3805 4400);
DISPLAY 0.638298 (-3805 4400);
PAINT MONO (-3805 4400);
FORCEPROP 2 LAST CDS_LIB standard
J 0
(-3550 4400);
DISPLAY INVISIBLE (-3550 4400);
FORCEPROP 1 LAST OFFPAGE TRUE
J 0
(-3225 4275);
DISPLAY 0.872340 (-3225 4275);
PAINT GREEN (-3225 4275);
DISPLAY INVISIBLE (-3225 4275);
FORCEPROP 1 LAST COMMENT_BODY TRUE
J 0
(-3450 4325);
DISPLAY 0.872340 (-3450 4325);
PAINT GREEN (-3450 4325);
DISPLAY INVISIBLE (-3450 4325);
FORCEPROP 2 LAST PATH I9
J 0
(-3800 4450);
DISPLAY 0.680851 (-3800 4450);
DISPLAY INVISIBLE (-3800 4450);
FORCEADD QUANTA_TITLE_BLOCK_C..1
(0 0);
FORCEPROP 0 LAST CDS_CON_LAST_MODIFIED Thu Sep 14 16:12:14 2023
J 0
(-1885 15);
DISPLAY INVISIBLE (-1885 15);
FORCEPROP 1 LAST CUSTOM_TXT_CDS <CON_LAST_MODIFIED>
J 0
(-1885 15);
DISPLAY 0.978723 (-1885 15);
FORCEPROP 2 LAST CUSTOM_TXT_CDS <XR_PAGE_TITLE>
J 0
(-7890 5250);
DISPLAY 0.638298 (-7890 5250);
PAINT PINK (-7890 5250);
DISPLAY INVISIBLE (-7890 5250);
FORCEPROP 1 LAST CUSTOM_TXT_CDS <NAME_2>
J 0
(-3175 50);
FORCEPROP 1 LAST CUSTOM_TXT_CDS <NAME_1>
J 0
(-3175 175);
FORCEPROP 1 LAST CUSTOM_TXT_CDS <Q_NUMBER>
J 0
(-1403 103);
DISPLAY 1.212766 (-1403 103);
FORCEPROP 1 LAST CUSTOM_TXT_CDS <Q_PROJ>
J 0
(-2382 102);
DISPLAY 1.212766 (-2382 102);
FORCEPROP 1 LAST CUSTOM_TXT_CDS <Q_REV>
J 0
(-184 103);
DISPLAY 1.212766 (-184 103);
FORCEPROP 1 LAST CUSTOM_TXT_CDS <CON_PAGE_NUM> OF <CON_TOTAL_PAGES>
J 0
(-446 18);
DISPLAY 0.978723 (-446 18);
FORCEPROP 1 LAST Q_TITLE WAKE
J 0
(-9225 75);
DISPLAY 2.446809 (-9225 75);
PAINT GREEN (-9225 75);
FORCEPROP 2 LAST PAGE_BORDER TRUE
J 0
(-7890 5250);
DISPLAY 0.638298 (-7890 5250);
PAINT PINK (-7890 5250);
DISPLAY INVISIBLE (-7890 5250);
FORCEPROP 1 LAST CDS_LMAN_SYM_OUTLINE -9475,6775,100,-125
J 0
(0 0);
DISPLAY 0.468085 (0 0);
PAINT GREEN (0 0);
DISPLAY INVISIBLE (0 0);
FORCEPROP 2 LAST CDS_LIB pure_quanta
J 0
(0 0);
DISPLAY INVISIBLE (0 0);
FORCEPROP 2 LAST CDS_XR_PAGE_TITLE CR-155 : @T6G_MB_LIB.T6G(SCH_1):PAGE155
J 0
(-7890 5250);
DISPLAY 0.638298 (-7890 5250);
PAINT PINK (-7890 5250);
DISPLAY INVISIBLE (-7890 5250);
FORCEPROP 1 LAST Q_DEPT BU9
J 1
(-3763 49);
DISPLAY 1.957447 (-3763 49);
PAINT GREEN (-3763 49);
DISPLAY INVISIBLE (-3763 49);
FORCEPROP 1 LAST COMMENT_BODY TRUE
J 0
(12 -13);
DISPLAY 0.978723 (12 -13);
PAINT GREEN (12 -13);
DISPLAY INVISIBLE (12 -13);
WIRE 16 -1 (-2775 4500)(-2900 4500);
WIRE 16 -1 (-2175 4500)(-2125 4500);
WIRE 16 -1 (-1175 4800)(-1175 4750);
WIRE 16 -1 (-4250 4875)(-4250 4775);
WIRE 16 -1 (-6025 3275)(-7250 3275);
FORCEPROP 0 LAST SIG_NAME IRQ_OCP_V3_2_WAKE_BUF_N
J 0
(-7110 3285);
DISPLAY 0.702128 (-7110 3285);
PAINT WHITE (-7110 3285);
WIRE 16 -1 (-6025 3450)(-7250 3450);
FORCEPROP 0 LAST SIG_NAME IRQ_OCP_SFF_WAKE_BUF_N
J 0
(-7110 3460);
DISPLAY 0.702128 (-7110 3460);
PAINT WHITE (-7110 3460);
WIRE 16 -1 (-5825 2975)(-4250 2975);
WIRE 16 -1 (-4250 3275)(-4250 2975);
WIRE 16 -1 (-4250 3450)(-4250 3275);
WIRE 16 -1 (-4250 3275)(-5825 3275);
WIRE 16 -1 (-4250 4450)(-4250 3450);
WIRE 16 -1 (-4250 3450)(-5825 3450);
WIRE 16 -1 (-4250 4450)(-2775 4450);
FORCEPROP 0 LAST SIG_NAME IRQ_LVC3_WAKE_N
J 0
(-4135 4460);
DISPLAY 0.489362 (-4135 4460);
FORCEPROP 2 LASTPROP $XRERR UNIQUE?
J 0
(-4375 4460);
DISPLAY 0.638298 (-4375 4460);
PAINT MONO (-4375 4460);
DISPLAY INVISIBLE (-4375 4460);
WIRE 16 -1 (-4250 4450)(-4250 4575);
WIRE 16 -1 (-7250 2975)(-6025 2975);
FORCEPROP 2 LAST SIG_NAME M2_0_PEWAKE_R_N
J 0
(-6975 2985);
DISPLAY 0.489362 (-6975 2985);
WIRE 16 -1 (-1625 4400)(-2175 4400);
FORCEPROP 0 LAST SIG_NAME IRQ_WAKE_R_N
J 0
(-1985 4410);
DISPLAY 0.489362 (-1985 4410);
FORCEPROP 2 LASTPROP $XRERR UNIQUE?
J 0
(-2225 4410);
DISPLAY 0.638298 (-2225 4410);
PAINT MONO (-2225 4410);
DISPLAY INVISIBLE (-2225 4410);
WIRE 16 -1 (-1175 4400)(-1150 4400);
WIRE 16 -1 (-1175 4550)(-1175 4400);
WIRE 16 -1 (-1175 4400)(-1425 4400);
FORCEPROP 0 LAST SIG_NAME IRQ_WAKE_N
J 0
(-1410 4410);
DISPLAY 0.489362 (-1410 4410);
WIRE 16 -1 (-3425 4125)(-3175 4125);
WIRE 16 -1 (-3425 4400)(-3425 4125);
WIRE 16 -1 (-3425 4400)(-2775 4400);
FORCEPROP 0 LAST SIG_NAME IRQ_LVC3_WAKE
J 0
(-3260 4410);
DISPLAY 0.489362 (-3260 4410);
WIRE 16 -1 (-3500 4400)(-3425 4400);
WIRE 16 -1 (-2725 4225)(-2725 4125);
WIRE 16 -1 (-2725 4125)(-2975 4125);
WIRE 16 -1 (-2175 4450)(-1700 4450);
FORCEPROP 0 LAST SIG_NAME IRQ_LVC3_WAKE
J 0
(-1985 4475);
DISPLAY 0.489362 (-1985 4475);
DOT 1 (-1175 4400);
DOT 1 (-4250 4450);
DOT 1 (-4250 3450);
DOT 1 (-4250 3275);
DOT 1 (-3425 4400);
FORCENOTE
OCP
(-8425 3325) 0;
DISPLAY LEFT (-8425 3325);
DISPLAY 3.148936 (-8425 3325);
PAINT WHITE (-8425 3325);
FORCENOTE
M.2
(-8450 2900) 0;
DISPLAY LEFT (-8450 2900);
DISPLAY 3.148936 (-8450 2900);
PAINT WHITE (-8450 2900);
QUIT
